# S9S_MB_2U (Grand Teton) — schematic netlist excerpt (pin names and nets, part order shuffled) for the footprints in the layout excerpt that follows; sources: Cadence DE-HDL packaged netlist, KiCad conversion of 03242023_DA0F0TMBIJ0_F0T_Motherboard_J_brd_V01_OCP.brd

C762  Q_CAP_DIFFBUS  DIFF BUS_0.22UF 6.3V 20% X6S  pkg C0201  page 176 : \1\ = P5E_CPU1_PE2_TX_C_DN<5> ; \2\ = P5E_CPU1_PE2_TX_DN<5>
R4125  Q_RES  4.7K 5% CHIP  pkg 0402LF  page 146 : A = P3V3_AUX ; B = GPU_3V3IO_RSVD0_FFU_N
R2992  Q_RES  0 5% CHIP  pkg 0402LF  page 234 : A = SMB_BMC_GPU_EN ; B = SMB_BMC_GPU_EN_R3

(kicad_pcb
	(version 20260206)
	(generator "pcbnew")
	(generator_version "10.0")
	(general
		(thickness 1.6)
		(legacy_teardrops no)
	)
	(paper "A4")
	(title_block
		(title "03242023_DA0F0TMBIJ0_F0T_Motherboard_J_brd_V01_OCP.brd")
		(comment 1 "Grand Teton / footprints 3968-3970 of 6105")
	)
	(layers
		(0 "F.Cu" signal "TOP")
		(4 "In1.Cu" signal "GND")
		(6 "In2.Cu" signal "IN1")
		(8 "In3.Cu" signal "GND1")
		(10 "In4.Cu" signal "IN2")
		(12 "In5.Cu" signal "GND2")
		(14 "In6.Cu" signal "IN3")
		(16 "In7.Cu" signal "GND3")
		(18 "In8.Cu" signal "VCC")
		(20 "In9.Cu" signal "VCC1")
		(22 "In10.Cu" signal "GND4")
		(24 "In11.Cu" signal "IN4")
		(26 "In12.Cu" signal "GND5")
		(28 "In13.Cu" signal "IN5")
		(30 "In14.Cu" signal "GND6")
		(32 "In15.Cu" signal "IN6")
		(34 "In16.Cu" signal "GND7")
		(2 "B.Cu" signal "BOTTOM")
		(9 "F.Adhes" user "F.Adhesive")
		(11 "B.Adhes" user "B.Adhesive")
		(13 "F.Paste" user "Package Geometry/Pastemask Top")
		(15 "B.Paste" user "Package Geometry/Pastemask Bottom")
		(5 "F.SilkS" user "Ref Des/Silkscreen Top")
		(7 "B.SilkS" user "Ref Des/Silkscreen Bottom")
		(1 "F.Mask" user "Board Geometry/Soldermask Top")
		(3 "B.Mask" user "Board Geometry/Soldermask Bottom")
		(17 "Dwgs.User" user "User.Drawings")
		(19 "Cmts.User" user "User.Comments")
		(21 "Eco1.User" user "User.Eco1")
		(23 "Eco2.User" user "User.Eco2")
		(25 "Edge.Cuts" user "Board Geometry/Outline")
		(27 "Margin" user)
		(31 "F.CrtYd" user "Package Geometry/Place Bound Top")
		(29 "B.CrtYd" user "Package Geometry/Place Bound Bottom")
		(35 "F.Fab" user "Ref Des/Assembly Top")
		(33 "B.Fab" user "Ref Des/Assembly Bottom")
	)
	(footprint ""
		(layer "F.Cu")
		(at 151.676354 -402.371052 -90)
		(property "Reference" "C762"
			(at 0 0 270)
			(layer "F.SilkS")
			(hide yes)
			(effects
				(font
					(size 1.27 1.27)
				)
			)
		)
		(property "Value" ""
			(at 0 0 270)
			(layer "F.Fab")
			(effects
				(font
					(size 1.27 1.27)
				)
			)
		)
		(duplicate_pad_numbers_are_jumpers no)
		(fp_line
			(start -0.299974 0.150114)
			(end -0.299974 -0.150114)
			(stroke
				(width 0.1)
				(type default)
			)
			(layer "F.Fab")
		)
		(fp_line
			(start 0.299974 0.150114)
			(end -0.299974 0.150114)
			(stroke
				(width 0.1)
				(type default)
			)
			(layer "F.Fab")
		)
		(fp_line
			(start -0.299974 -0.150114)
			(end 0.299974 -0.150114)
			(stroke
				(width 0.1)
				(type default)
			)
			(layer "F.Fab")
		)
		(fp_line
			(start 0.299974 -0.150114)
			(end 0.299974 0.150114)
			(stroke
				(width 0.1)
				(type default)
			)
			(layer "F.Fab")
		)
		(pad "1" smd rect
			(at -0.2667 0 270)
			(size 0.3048 0.381)
			(layers "F.Cu" "F.Mask" "F.Paste")
			(net "P5E_CPU1_PE2_TX_C_DN<5>")
		)
		(pad "2" smd rect
			(at 0.2667 0 270)
			(size 0.3048 0.381)
			(layers "F.Cu" "F.Mask" "F.Paste")
			(net "P5E_CPU1_PE2_TX_DN<5>")
		)
	)
	(footprint ""
		(layer "F.Cu")
		(at 44.848018 -437.792368 180)
		(property "Reference" "R2992"
			(at 0 0 180)
			(layer "F.SilkS")
			(hide yes)
			(effects
				(font
					(size 1.27 1.27)
				)
			)
		)
		(property "Value" ""
			(at 0 0 180)
			(layer "F.Fab")
			(effects
				(font
					(size 1.27 1.27)
				)
			)
		)
		(duplicate_pad_numbers_are_jumpers no)
		(fp_line
			(start 0.7874 0.4064)
			(end -0.7874 0.4064)
			(stroke
				(width 0.1524)
				(type default)
			)
			(layer "F.SilkS")
		)
		(fp_line
			(start 0.7874 -0.4064)
			(end 0.7874 0.4064)
			(stroke
				(width 0.1524)
				(type default)
			)
			(layer "F.SilkS")
		)
		(fp_line
			(start -0.7874 0.4064)
			(end -0.7874 -0.4064)
			(stroke
				(width 0.1524)
				(type default)
			)
			(layer "F.SilkS")
		)
		(fp_line
			(start -0.7874 -0.4064)
			(end 0.7874 -0.4064)
			(stroke
				(width 0.1524)
				(type default)
			)
			(layer "F.SilkS")
		)
		(fp_line
			(start 0.67945 0.3048)
			(end 0.120396 0.3048)
			(stroke
				(width 0.1)
				(type default)
			)
			(layer "F.Fab")
		)
		(fp_line
			(start 0.67945 -0.3048)
			(end 0.67945 0.3048)
			(stroke
				(width 0.1)
				(type default)
			)
			(layer "F.Fab")
		)
		(fp_line
			(start 0.12065 -0.2794)
			(end 0.12065 -0.3048)
			(stroke
				(width 0.1)
				(type default)
			)
			(layer "F.Fab")
		)
		(fp_line
			(start 0.12065 -0.3048)
			(end 0.67945 -0.3048)
			(stroke
				(width 0.1)
				(type default)
			)
			(layer "F.Fab")
		)
		(fp_line
			(start 0.120396 0.3048)
			(end 0.120396 0.2794)
			(stroke
				(width 0.1)
				(type default)
			)
			(layer "F.Fab")
		)
		(fp_line
			(start 0.120396 0.2794)
			(end -0.12065 0.2794)
			(stroke
				(width 0.1)
				(type default)
			)
			(layer "F.Fab")
		)
		(fp_line
			(start -0.12065 0.3048)
			(end -0.67945 0.3048)
			(stroke
				(width 0.1)
				(type default)
			)
			(layer "F.Fab")
		)
		(fp_line
			(start -0.12065 0.2794)
			(end -0.12065 0.3048)
			(stroke
				(width 0.1)
				(type default)
			)
			(layer "F.Fab")
		)
		(fp_line
			(start -0.12065 -0.2794)
			(end 0.12065 -0.2794)
			(stroke
				(width 0.1)
				(type default)
			)
			(layer "F.Fab")
		)
		(fp_line
			(start -0.12065 -0.305054)
			(end -0.12065 -0.2794)
			(stroke
				(width 0.1)
				(type default)
			)
			(layer "F.Fab")
		)
		(fp_line
			(start -0.67945 0.3048)
			(end -0.67945 -0.305054)
			(stroke
				(width 0.1)
				(type default)
			)
			(layer "F.Fab")
		)
		(fp_line
			(start -0.67945 -0.305054)
			(end -0.12065 -0.305054)
			(stroke
				(width 0.1)
				(type default)
			)
			(layer "F.Fab")
		)
		(pad "1" smd circle
			(at -0.40005 0 180)
			(size 0 0)
			(layers "F.Cu" "F.Mask" "F.Paste")
			(net "SMB_BMC_GPU_EN")
		)
		(pad "2" smd circle
			(at 0.40005 0 180)
			(size 0 0)
			(layers "F.Cu" "F.Mask" "F.Paste")
			(net "SMB_BMC_GPU_EN_R3")
		)
	)
	(footprint ""
		(layer "F.Cu")
		(at 303.821084 -426.557186 -90)
		(property "Reference" "R4125"
			(at 0 0 270)
			(layer "F.SilkS")
			(hide yes)
			(effects
				(font
					(size 1.27 1.27)
				)
			)
		)
		(property "Value" ""
			(at 0 0 270)
			(layer "F.Fab")
			(effects
				(font
					(size 1.27 1.27)
				)
			)
		)
		(duplicate_pad_numbers_are_jumpers no)
		(fp_line
			(start -0.7874 0.4064)
			(end -0.7874 -0.4064)
			(stroke
				(width 0.1524)
				(type default)
			)
			(layer "F.SilkS")
		)
		(fp_line
			(start 0.7874 0.4064)
			(end -0.7874 0.4064)
			(stroke
				(width 0.1524)
				(type default)
			)
			(layer "F.SilkS")
		)
		(fp_line
			(start -0.7874 -0.4064)
			(end 0.7874 -0.4064)
			(stroke
				(width 0.1524)
				(type default)
			)
			(layer "F.SilkS")
		)
		(fp_line
			(start 0.7874 -0.4064)
			(end 0.7874 0.4064)
			(stroke
				(width 0.1524)
				(type default)
			)
			(layer "F.SilkS")
		)
		(fp_line
			(start -0.67945 0.3048)
			(end -0.67945 -0.305054)
			(stroke
				(width 0.1)
				(type default)
			)
			(layer "F.Fab")
		)
		(fp_line
			(start -0.12065 0.3048)
			(end -0.67945 0.3048)
			(stroke
				(width 0.1)
				(type default)
			)
			(layer "F.Fab")
		)
		(fp_line
			(start 0.120396 0.3048)
			(end 0.120396 0.2794)
			(stroke
				(width 0.1)
				(type default)
			)
			(layer "F.Fab")
		)
		(fp_line
			(start 0.67945 0.3048)
			(end 0.120396 0.3048)
			(stroke
				(width 0.1)
				(type default)
			)
			(layer "F.Fab")
		)
		(fp_line
			(start -0.12065 0.2794)
			(end -0.12065 0.3048)
			(stroke
				(width 0.1)
				(type default)
			)
			(layer "F.Fab")
		)
		(fp_line
			(start 0.120396 0.2794)
			(end -0.12065 0.2794)
			(stroke
				(width 0.1)
				(type default)
			)
			(layer "F.Fab")
		)
		(fp_line
			(start -0.12065 -0.2794)
			(end 0.12065 -0.2794)
			(stroke
				(width 0.1)
				(type default)
			)
			(layer "F.Fab")
		)
		(fp_line
			(start 0.12065 -0.2794)
			(end 0.12065 -0.3048)
			(stroke
				(width 0.1)
				(type default)
			)
			(layer "F.Fab")
		)
		(fp_line
			(start 0.12065 -0.3048)
			(end 0.67945 -0.3048)
			(stroke
				(width 0.1)
				(type default)
			)
			(layer "F.Fab")
		)
		(fp_line
			(start 0.67945 -0.3048)
			(end 0.67945 0.3048)
			(stroke
				(width 0.1)
				(type default)
			)
			(layer "F.Fab")
		)
		(fp_line
			(start -0.67945 -0.305054)
			(end -0.12065 -0.305054)
			(stroke
				(width 0.1)
				(type default)
			)
			(layer "F.Fab")
		)
		(fp_line
			(start -0.12065 -0.305054)
			(end -0.12065 -0.2794)
			(stroke
				(width 0.1)
				(type default)
			)
			(layer "F.Fab")
		)
		(pad "1" smd circle
			(at -0.40005 0 270)
			(size 0 0)
			(layers "F.Cu" "F.Mask" "F.Paste")
			(net "P3V3_AUX")
		)
		(pad "2" smd circle
			(at 0.40005 0 270)
			(size 0 0)
			(layers "F.Cu" "F.Mask" "F.Paste")
			(net "GPU_3V3IO_RSVD0_FFU_N")
		)
	)
)
